("..\\packaged\\pstdmlmodels.dat" 
 (PackagedDevice 
  (DEFAULT_CAPACITOR_100000pF_2_1 
   (ESpice ".subckt DEFAULT_CAPACITOR_100000pF_2_1 1 2
C1 1 2 1e-007
.ends DEFAULT_CAPACITOR_100000pF_2_1
" ) 
   (PinConnections 
    (1 2 ) 
    (2 1 ) ) ) 
  (DEFAULT_CAPACITOR_10000pF_2_1 
   (ESpice ".subckt DEFAULT_CAPACITOR_10000pF_2_1 1 2
C1 1 2 1e-008
.ends DEFAULT_CAPACITOR_10000pF_2_1
" ) 
   (PinConnections 
    (1 2 ) 
    (2 1 ) ) ) ) 
 (LibraryVersion 136.2 ) ) 